# T6G (Grand Teton) — schematic netlist excerpt (pin names and nets, part order shuffled) for the footprints in the layout excerpt that follows; sources: Cadence DE-HDL packaged netlist, KiCad conversion of 04192023_DAF0TMB3IC0_F0TG_MB_C_brd_V02_OCP.brd

U194  LTC4307CMS8  IC  pkg MSOP8  page 248
  ENABLE  = SMB_BMC_GPU_EN_R1
  SCL_OUT  = SMB_1_BMC_GPU_BUF_R_SCL
  SCL_IN  = SMB_1_BMC_GPU_R_SCL
  GND  = GND
  READY  = NC
  SDA_IN  = SMB_1_BMC_GPU_R_SDA
  SDA_OUT  = SMB_1_BMC_GPU_BUF_R_SDA
  VCC  = P3V3_AUX

(kicad_pcb
	(version 20260206)
	(generator "pcbnew")
	(generator_version "10.0")
	(general
		(thickness 1.6)
		(legacy_teardrops no)
	)
	(paper "A4")
	(title_block
		(title "04192023_DAF0TMB3IC0_F0TG_MB_C_brd_V02_OCP.brd")
		(comment 1 "Grand Teton / footprints 3542-3542 of 8354")
	)
	(layers
		(0 "F.Cu" signal "TOP")
		(4 "In1.Cu" signal "GND")
		(6 "In2.Cu" signal "IN1")
		(8 "In3.Cu" signal "GND1")
		(10 "In4.Cu" signal "IN2")
		(12 "In5.Cu" signal "GND2")
		(14 "In6.Cu" signal "IN3")
		(16 "In7.Cu" signal "GND3")
		(18 "In8.Cu" signal "VCC")
		(20 "In9.Cu" signal "VCC1")
		(22 "In10.Cu" signal "GND4")
		(24 "In11.Cu" signal "IN4")
		(26 "In12.Cu" signal "GND5")
		(28 "In13.Cu" signal "IN5")
		(30 "In14.Cu" signal "GND6")
		(32 "In15.Cu" signal "IN6")
		(34 "In16.Cu" signal "GND7")
		(2 "B.Cu" signal "BOTTOM")
		(9 "F.Adhes" user "F.Adhesive")
		(11 "B.Adhes" user "B.Adhesive")
		(13 "F.Paste" user "Package Geometry/Pastemask Top")
		(15 "B.Paste" user "Package Geometry/Pastemask Bottom")
		(5 "F.SilkS" user "Ref Des/Silkscreen Top")
		(7 "B.SilkS" user "Ref Des/Silkscreen Bottom")
		(1 "F.Mask" user "Board Geometry/Soldermask Top")
		(3 "B.Mask" user "Board Geometry/Soldermask Bottom")
		(17 "Dwgs.User" user "User.Drawings")
		(19 "Cmts.User" user "User.Comments")
		(21 "Eco1.User" user "User.Eco1")
		(23 "Eco2.User" user "User.Eco2")
		(25 "Edge.Cuts" user "Board Geometry/Outline")
		(27 "Margin" user)
		(31 "F.CrtYd" user "Package Geometry/Place Bound Top")
		(29 "B.CrtYd" user "Package Geometry/Place Bound Bottom")
		(35 "F.Fab" user "Ref Des/Assembly Top")
		(33 "B.Fab" user "Ref Des/Assembly Bottom")
	)
	(footprint ""
		(layer "F.Cu")
		(at 28.274772 -432.477164)
		(property "Reference" "U194"
			(at -4.766818 -2.04216 0)
			(unlocked yes)
			(layer "F.SilkS")
			(effects
				(font
					(size 0.7874 0.5842)
					(thickness 0.1524)
				)
				(justify left)
			)
		)
		(property "Value" ""
			(at 0 0 0)
			(layer "F.Fab")
			(effects
				(font
					(size 1.27 1.27)
				)
			)
		)
		(duplicate_pad_numbers_are_jumpers no)
		(fp_line
			(start -1.3716 -1.524)
			(end -0.508 -1.524)
			(stroke
				(width 0.1524)
				(type default)
			)
			(layer "F.SilkS")
		)
		(fp_line
			(start -1.3716 1.524)
			(end -1.3716 -1.524)
			(stroke
				(width 0.1524)
				(type default)
			)
			(layer "F.SilkS")
		)
		(fp_line
			(start -0.508 -1.524)
			(end 0 -1.016)
			(stroke
				(width 0.1524)
				(type default)
			)
			(layer "F.SilkS")
		)
		(fp_line
			(start 0 -1.016)
			(end 0.508 -1.524)
			(stroke
				(width 0.1524)
				(type default)
			)
			(layer "F.SilkS")
		)
		(fp_line
			(start 0.508 -1.524)
			(end 1.3716 -1.524)
			(stroke
				(width 0.1524)
				(type default)
			)
			(layer "F.SilkS")
		)
		(fp_line
			(start 1.3716 -1.524)
			(end 1.3716 1.524)
			(stroke
				(width 0.1524)
				(type default)
			)
			(layer "F.SilkS")
		)
		(fp_line
			(start 1.3716 1.524)
			(end -1.3716 1.524)
			(stroke
				(width 0.1524)
				(type default)
			)
			(layer "F.SilkS")
		)
		(fp_poly
			(pts
				(xy -3.651758 -1.010666) (xy -3.47345 -1.609598) (xy -3.03657 -1.137158)
			)
			(stroke
				(width 0)
				(type default)
			)
			(fill yes)
			(layer "F.SilkS")
		)
		(fp_line
			(start -2.54 -1.0668)
			(end -1.5494 -1.0668)
			(stroke
				(width 0.1)
				(type default)
			)
			(layer "F.Fab")
		)
		(fp_line
			(start -2.54 1.0668)
			(end -2.54 -1.0668)
			(stroke
				(width 0.1)
				(type default)
			)
			(layer "F.Fab")
		)
		(fp_line
			(start -1.5494 -1.524)
			(end 1.5494 -1.524)
			(stroke
				(width 0.1)
				(type default)
			)
			(layer "F.Fab")
		)
		(fp_line
			(start -1.5494 -1.0668)
			(end -1.5494 -1.524)
			(stroke
				(width 0.1)
				(type default)
			)
			(layer "F.Fab")
		)
		(fp_line
			(start -1.5494 1.0668)
			(end -2.54 1.0668)
			(stroke
				(width 0.1)
				(type default)
			)
			(layer "F.Fab")
		)
		(fp_line
			(start -1.5494 1.0668)
			(end -1.5494 -1.0668)
			(stroke
				(width 0.1)
				(type default)
			)
			(layer "F.Fab")
		)
		(fp_line
			(start -1.5494 1.524)
			(end -1.5494 1.0668)
			(stroke
				(width 0.1)
				(type default)
			)
			(layer "F.Fab")
		)
		(fp_line
			(start 1.5494 -1.524)
			(end 1.5494 -1.0668)
			(stroke
				(width 0.1)
				(type default)
			)
			(layer "F.Fab")
		)
		(fp_line
			(start 1.5494 -1.0668)
			(end 1.5494 1.0668)
			(stroke
				(width 0.1)
				(type default)
			)
			(layer "F.Fab")
		)
		(fp_line
			(start 1.5494 -1.0668)
			(end 2.54 -1.0668)
			(stroke
				(width 0.1)
				(type default)
			)
			(layer "F.Fab")
		)
		(fp_line
			(start 1.5494 1.0668)
			(end 1.5494 1.524)
			(stroke
				(width 0.1)
				(type default)
			)
			(layer "F.Fab")
		)
		(fp_line
			(start 1.5494 1.524)
			(end -1.5494 1.524)
			(stroke
				(width 0.1)
				(type default)
			)
			(layer "F.Fab")
		)
		(fp_line
			(start 2.54 -1.0668)
			(end 2.54 1.0668)
			(stroke
				(width 0.1)
				(type default)
			)
			(layer "F.Fab")
		)
		(fp_line
			(start 2.54 1.0668)
			(end 1.5494 1.0668)
			(stroke
				(width 0.1)
				(type default)
			)
			(layer "F.Fab")
		)
		(fp_poly
			(pts
				(xy -3.60172 -0.719328) (xy -3.60172 -1.344168) (xy -3.048 -1.016)
			)
			(stroke
				(width 0)
				(type default)
			)
			(fill yes)
			(layer "F.Fab")
		)
		(pad "1" smd rect
			(at -2.232406 -0.975106 270)
			(size 0.3556 1.4224)
			(layers "F.Cu" "F.Mask" "F.Paste")
			(net "SMB_BMC_GPU_EN_R1")
		)
		(pad "2" smd rect
			(at -2.232406 -0.32512 270)
			(size 0.3556 1.4224)
			(layers "F.Cu" "F.Mask" "F.Paste")
			(net "SMB_1_BMC_GPU_BUF_R_SCL")
		)
		(pad "3" smd rect
			(at -2.232406 0.32512 270)
			(size 0.3556 1.4224)
			(layers "F.Cu" "F.Mask" "F.Paste")
			(net "SMB_1_BMC_GPU_R_SCL")
		)
		(pad "4" smd rect
			(at -2.232406 0.975106 270)
			(size 0.3556 1.4224)
			(layers "F.Cu" "F.Mask" "F.Paste")
			(net "GND")
		)
		(pad "5" smd rect
			(at 2.232406 0.975106 270)
			(size 0.3556 1.4224)
			(layers "F.Cu" "F.Mask" "F.Paste")
			(net "Net_10760")
		)
		(pad "6" smd rect
			(at 2.232406 0.32512 270)
			(size 0.3556 1.4224)
			(layers "F.Cu" "F.Mask" "F.Paste")
			(net "SMB_1_BMC_GPU_R_SDA")
		)
		(pad "7" smd rect
			(at 2.232406 -0.32512 270)
			(size 0.3556 1.4224)
			(layers "F.Cu" "F.Mask" "F.Paste")
			(net "SMB_1_BMC_GPU_BUF_R_SDA")
		)
		(pad "8" smd rect
			(at 2.232406 -0.975106 270)
			(size 0.3556 1.4224)
			(layers "F.Cu" "F.Mask" "F.Paste")
			(net "P3V3_AUX")
		)
	)
)
